# S9S_MB_2U (Grand Teton) — schematic netlist excerpt (pin names and nets, part order shuffled) for the footprints in the layout excerpt that follows; sources: Cadence DE-HDL packaged netlist, KiCad conversion of 03242023_DA0F0TMBIJ0_F0T_Motherboard_J_brd_V01_OCP.brd

R3882  Q_RES  49.9 1% CHIP  pkg 0402LF  page 89 : A = I3C_SPD_DDRABCD_CPU0_LVC1_SCL_7 ; B = I3C_SPD_DDRABCD_CPU0_LVC1_SCL
R1244  Q_RES  301 1% CHIP  pkg 0402LF  page 117 : A = PVNN_TERM_CPU1 ; B = H_CPU_PM_FAST_WAKE_N

(kicad_pcb
	(version 20260206)
	(generator "pcbnew")
	(generator_version "10.0")
	(general
		(thickness 1.6)
		(legacy_teardrops no)
	)
	(paper "A4")
	(title_block
		(title "03242023_DA0F0TMBIJ0_F0T_Motherboard_J_brd_V01_OCP.brd")
		(comment 1 "Grand Teton / footprints 4558-4559 of 6105")
	)
	(layers
		(0 "F.Cu" signal "TOP")
		(4 "In1.Cu" signal "GND")
		(6 "In2.Cu" signal "IN1")
		(8 "In3.Cu" signal "GND1")
		(10 "In4.Cu" signal "IN2")
		(12 "In5.Cu" signal "GND2")
		(14 "In6.Cu" signal "IN3")
		(16 "In7.Cu" signal "GND3")
		(18 "In8.Cu" signal "VCC")
		(20 "In9.Cu" signal "VCC1")
		(22 "In10.Cu" signal "GND4")
		(24 "In11.Cu" signal "IN4")
		(26 "In12.Cu" signal "GND5")
		(28 "In13.Cu" signal "IN5")
		(30 "In14.Cu" signal "GND6")
		(32 "In15.Cu" signal "IN6")
		(34 "In16.Cu" signal "GND7")
		(2 "B.Cu" signal "BOTTOM")
		(9 "F.Adhes" user "F.Adhesive")
		(11 "B.Adhes" user "B.Adhesive")
		(13 "F.Paste" user "Package Geometry/Pastemask Top")
		(15 "B.Paste" user "Package Geometry/Pastemask Bottom")
		(5 "F.SilkS" user "Ref Des/Silkscreen Top")
		(7 "B.SilkS" user "Ref Des/Silkscreen Bottom")
		(1 "F.Mask" user "Board Geometry/Soldermask Top")
		(3 "B.Mask" user "Board Geometry/Soldermask Bottom")
		(17 "Dwgs.User" user "User.Drawings")
		(19 "Cmts.User" user "User.Comments")
		(21 "Eco1.User" user "User.Eco1")
		(23 "Eco2.User" user "User.Eco2")
		(25 "Edge.Cuts" user "Board Geometry/Outline")
		(27 "Margin" user)
		(31 "F.CrtYd" user "Package Geometry/Place Bound Top")
		(29 "B.CrtYd" user "Package Geometry/Place Bound Bottom")
		(35 "F.Fab" user "Ref Des/Assembly Top")
		(33 "B.Fab" user "Ref Des/Assembly Bottom")
	)
	(footprint ""
		(layer "B.Cu")
		(at 261.73557 -317.881762 180)
		(property "Reference" "R3882"
			(at 0 0 0)
			(layer "B.SilkS")
			(hide yes)
			(effects
				(font
					(size 1.27 1.27)
				)
				(justify mirror)
			)
		)
		(property "Value" ""
			(at 0 0 0)
			(layer "B.Fab")
			(effects
				(font
					(size 1.27 1.27)
				)
				(justify mirror)
			)
		)
		(duplicate_pad_numbers_are_jumpers no)
		(fp_line
			(start 0.7874 0.4064)
			(end 0.7874 -0.4064)
			(stroke
				(width 0.1524)
				(type default)
			)
			(layer "B.SilkS")
		)
		(fp_line
			(start 0.7874 -0.4064)
			(end -0.7874 -0.4064)
			(stroke
				(width 0.1524)
				(type default)
			)
			(layer "B.SilkS")
		)
		(fp_line
			(start -0.7874 0.4064)
			(end 0.7874 0.4064)
			(stroke
				(width 0.1524)
				(type default)
			)
			(layer "B.SilkS")
		)
		(fp_line
			(start -0.7874 -0.4064)
			(end -0.7874 0.4064)
			(stroke
				(width 0.1524)
				(type default)
			)
			(layer "B.SilkS")
		)
		(fp_line
			(start 0.67945 0.3048)
			(end 0.67945 -0.305054)
			(stroke
				(width 0.1)
				(type default)
			)
			(layer "B.Fab")
		)
		(fp_line
			(start 0.67945 -0.305054)
			(end 0.12065 -0.305054)
			(stroke
				(width 0.1)
				(type default)
			)
			(layer "B.Fab")
		)
		(fp_line
			(start 0.12065 0.3048)
			(end 0.67945 0.3048)
			(stroke
				(width 0.1)
				(type default)
			)
			(layer "B.Fab")
		)
		(fp_line
			(start 0.12065 0.2794)
			(end 0.12065 0.3048)
			(stroke
				(width 0.1)
				(type default)
			)
			(layer "B.Fab")
		)
		(fp_line
			(start 0.12065 -0.2794)
			(end -0.12065 -0.2794)
			(stroke
				(width 0.1)
				(type default)
			)
			(layer "B.Fab")
		)
		(fp_line
			(start 0.12065 -0.305054)
			(end 0.12065 -0.2794)
			(stroke
				(width 0.1)
				(type default)
			)
			(layer "B.Fab")
		)
		(fp_line
			(start -0.120396 0.3048)
			(end -0.120396 0.2794)
			(stroke
				(width 0.1)
				(type default)
			)
			(layer "B.Fab")
		)
		(fp_line
			(start -0.120396 0.2794)
			(end 0.12065 0.2794)
			(stroke
				(width 0.1)
				(type default)
			)
			(layer "B.Fab")
		)
		(fp_line
			(start -0.12065 -0.2794)
			(end -0.12065 -0.3048)
			(stroke
				(width 0.1)
				(type default)
			)
			(layer "B.Fab")
		)
		(fp_line
			(start -0.12065 -0.3048)
			(end -0.67945 -0.3048)
			(stroke
				(width 0.1)
				(type default)
			)
			(layer "B.Fab")
		)
		(fp_line
			(start -0.67945 0.3048)
			(end -0.120396 0.3048)
			(stroke
				(width 0.1)
				(type default)
			)
			(layer "B.Fab")
		)
		(fp_line
			(start -0.67945 -0.3048)
			(end -0.67945 0.3048)
			(stroke
				(width 0.1)
				(type default)
			)
			(layer "B.Fab")
		)
		(pad "1" smd circle
			(at 0.40005 0)
			(size 0 0)
			(layers "B.Cu" "B.Mask" "B.Paste")
			(net "I3C_SPD_DDRABCD_CPU0_LVC1_SCL_7")
		)
		(pad "2" smd circle
			(at -0.40005 0)
			(size 0 0)
			(layers "B.Cu" "B.Mask" "B.Paste")
			(net "I3C_SPD_DDRABCD_CPU0_LVC1_SCL")
		)
	)
	(footprint ""
		(layer "B.Cu")
		(at 154.4955 -190.87211 -90)
		(property "Reference" "R1244"
			(at 0 0 90)
			(layer "B.SilkS")
			(hide yes)
			(effects
				(font
					(size 1.27 1.27)
				)
				(justify mirror)
			)
		)
		(property "Value" ""
			(at 0 0 90)
			(layer "B.Fab")
			(effects
				(font
					(size 1.27 1.27)
				)
				(justify mirror)
			)
		)
		(duplicate_pad_numbers_are_jumpers no)
		(fp_line
			(start -0.7874 0.4064)
			(end 0.7874 0.4064)
			(stroke
				(width 0.1524)
				(type default)
			)
			(layer "B.SilkS")
		)
		(fp_line
			(start 0.7874 0.4064)
			(end 0.7874 -0.4064)
			(stroke
				(width 0.1524)
				(type default)
			)
			(layer "B.SilkS")
		)
		(fp_line
			(start -0.7874 -0.4064)
			(end -0.7874 0.4064)
			(stroke
				(width 0.1524)
				(type default)
			)
			(layer "B.SilkS")
		)
		(fp_line
			(start 0.7874 -0.4064)
			(end -0.7874 -0.4064)
			(stroke
				(width 0.1524)
				(type default)
			)
			(layer "B.SilkS")
		)
		(fp_line
			(start -0.67945 0.3048)
			(end -0.120396 0.3048)
			(stroke
				(width 0.1)
				(type default)
			)
			(layer "B.Fab")
		)
		(fp_line
			(start -0.120396 0.3048)
			(end -0.120396 0.2794)
			(stroke
				(width 0.1)
				(type default)
			)
			(layer "B.Fab")
		)
		(fp_line
			(start 0.12065 0.3048)
			(end 0.67945 0.3048)
			(stroke
				(width 0.1)
				(type default)
			)
			(layer "B.Fab")
		)
		(fp_line
			(start 0.67945 0.3048)
			(end 0.67945 -0.305054)
			(stroke
				(width 0.1)
				(type default)
			)
			(layer "B.Fab")
		)
		(fp_line
			(start -0.120396 0.2794)
			(end 0.12065 0.2794)
			(stroke
				(width 0.1)
				(type default)
			)
			(layer "B.Fab")
		)
		(fp_line
			(start 0.12065 0.2794)
			(end 0.12065 0.3048)
			(stroke
				(width 0.1)
				(type default)
			)
			(layer "B.Fab")
		)
		(fp_line
			(start -0.12065 -0.2794)
			(end -0.12065 -0.3048)
			(stroke
				(width 0.1)
				(type default)
			)
			(layer "B.Fab")
		)
		(fp_line
			(start 0.12065 -0.2794)
			(end -0.12065 -0.2794)
			(stroke
				(width 0.1)
				(type default)
			)
			(layer "B.Fab")
		)
		(fp_line
			(start -0.67945 -0.3048)
			(end -0.67945 0.3048)
			(stroke
				(width 0.1)
				(type default)
			)
			(layer "B.Fab")
		)
		(fp_line
			(start -0.12065 -0.3048)
			(end -0.67945 -0.3048)
			(stroke
				(width 0.1)
				(type default)
			)
			(layer "B.Fab")
		)
		(fp_line
			(start 0.12065 -0.305054)
			(end 0.12065 -0.2794)
			(stroke
				(width 0.1)
				(type default)
			)
			(layer "B.Fab")
		)
		(fp_line
			(start 0.67945 -0.305054)
			(end 0.12065 -0.305054)
			(stroke
				(width 0.1)
				(type default)
			)
			(layer "B.Fab")
		)
		(pad "1" smd circle
			(at 0.40005 0 90)
			(size 0 0)
			(layers "B.Cu" "B.Mask" "B.Paste")
			(net "PVNN_TERM_CPU1")
		)
		(pad "2" smd circle
			(at -0.40005 0 90)
			(size 0 0)
			(layers "B.Cu" "B.Mask" "B.Paste")
			(net "H_CPU_PM_FAST_WAKE_N")
		)
	)
)
